# S9S_MB_2U (Grand Teton) — schematic netlist excerpt (pin names and nets, part order shuffled) for the footprints in the layout excerpt that follows; sources: Cadence DE-HDL packaged netlist, KiCad conversion of 03242023_DA0F0TMBIJ0_F0T_Motherboard_J_brd_V01_OCP.brd

R1329  Q_RES  2K 1% EMPTY  pkg 0402LF  page 219 : A = PWRGD_DRAMPWRGD_CPU1_AB_R_LVC1 ; B = GND
C160  Q_CAP_DIFFBUS  DIFF BUS_0.22UF 6.3V 20% X6S  pkg C0201  page 178 : \1\ = DMI_CPU0_PCH_RX_C_DP<5> ; \2\ = DMI_CPU0_PCH_RX_DP<5>
C2293  Q_CAP  0.1UF 25V 10% EMPTY  pkg 0402  page 245 : A = RST_SMB_SWITCH_R_N ; B = GND

(kicad_pcb
	(version 20260206)
	(generator "pcbnew")
	(generator_version "10.0")
	(general
		(thickness 1.6)
		(legacy_teardrops no)
	)
	(paper "A4")
	(title_block
		(title "03242023_DA0F0TMBIJ0_F0T_Motherboard_J_brd_V01_OCP.brd")
		(comment 1 "Grand Teton / footprints 4454-4456 of 6105")
	)
	(layers
		(0 "F.Cu" signal "TOP")
		(4 "In1.Cu" signal "GND")
		(6 "In2.Cu" signal "IN1")
		(8 "In3.Cu" signal "GND1")
		(10 "In4.Cu" signal "IN2")
		(12 "In5.Cu" signal "GND2")
		(14 "In6.Cu" signal "IN3")
		(16 "In7.Cu" signal "GND3")
		(18 "In8.Cu" signal "VCC")
		(20 "In9.Cu" signal "VCC1")
		(22 "In10.Cu" signal "GND4")
		(24 "In11.Cu" signal "IN4")
		(26 "In12.Cu" signal "GND5")
		(28 "In13.Cu" signal "IN5")
		(30 "In14.Cu" signal "GND6")
		(32 "In15.Cu" signal "IN6")
		(34 "In16.Cu" signal "GND7")
		(2 "B.Cu" signal "BOTTOM")
		(9 "F.Adhes" user "F.Adhesive")
		(11 "B.Adhes" user "B.Adhesive")
		(13 "F.Paste" user "Package Geometry/Pastemask Top")
		(15 "B.Paste" user "Package Geometry/Pastemask Bottom")
		(5 "F.SilkS" user "Ref Des/Silkscreen Top")
		(7 "B.SilkS" user "Ref Des/Silkscreen Bottom")
		(1 "F.Mask" user "Board Geometry/Soldermask Top")
		(3 "B.Mask" user "Board Geometry/Soldermask Bottom")
		(17 "Dwgs.User" user "User.Drawings")
		(19 "Cmts.User" user "User.Comments")
		(21 "Eco1.User" user "User.Eco1")
		(23 "Eco2.User" user "User.Eco2")
		(25 "Edge.Cuts" user "Board Geometry/Outline")
		(27 "Margin" user)
		(31 "F.CrtYd" user "Package Geometry/Place Bound Top")
		(29 "B.CrtYd" user "Package Geometry/Place Bound Bottom")
		(35 "F.Fab" user "Ref Des/Assembly Top")
		(33 "B.Fab" user "Ref Des/Assembly Bottom")
	)
	(footprint ""
		(layer "B.Cu")
		(at 239.2934 -422.9862 90)
		(property "Reference" "C2293"
			(at 0 0 90)
			(layer "B.SilkS")
			(hide yes)
			(effects
				(font
					(size 1.27 1.27)
				)
				(justify mirror)
			)
		)
		(property "Value" ""
			(at 0 0 90)
			(layer "B.Fab")
			(effects
				(font
					(size 1.27 1.27)
				)
				(justify mirror)
			)
		)
		(duplicate_pad_numbers_are_jumpers no)
		(fp_line
			(start 0.7874 -0.4064)
			(end -0.7874 -0.4064)
			(stroke
				(width 0.1524)
				(type default)
			)
			(layer "B.SilkS")
		)
		(fp_line
			(start -0.7874 -0.4064)
			(end -0.7874 0.4064)
			(stroke
				(width 0.1524)
				(type default)
			)
			(layer "B.SilkS")
		)
		(fp_line
			(start 0.7874 0.4064)
			(end 0.7874 -0.4064)
			(stroke
				(width 0.1524)
				(type default)
			)
			(layer "B.SilkS")
		)
		(fp_line
			(start -0.7874 0.4064)
			(end 0.7874 0.4064)
			(stroke
				(width 0.1524)
				(type default)
			)
			(layer "B.SilkS")
		)
		(fp_line
			(start 0.67945 -0.305054)
			(end 0.12065 -0.305054)
			(stroke
				(width 0.1)
				(type default)
			)
			(layer "B.Fab")
		)
		(fp_line
			(start 0.12065 -0.305054)
			(end 0.12065 -0.2794)
			(stroke
				(width 0.1)
				(type default)
			)
			(layer "B.Fab")
		)
		(fp_line
			(start -0.12065 -0.3048)
			(end -0.67945 -0.3048)
			(stroke
				(width 0.1)
				(type default)
			)
			(layer "B.Fab")
		)
		(fp_line
			(start -0.67945 -0.3048)
			(end -0.67945 0.3048)
			(stroke
				(width 0.1)
				(type default)
			)
			(layer "B.Fab")
		)
		(fp_line
			(start 0.12065 -0.2794)
			(end -0.12065 -0.2794)
			(stroke
				(width 0.1)
				(type default)
			)
			(layer "B.Fab")
		)
		(fp_line
			(start -0.12065 -0.2794)
			(end -0.12065 -0.3048)
			(stroke
				(width 0.1)
				(type default)
			)
			(layer "B.Fab")
		)
		(fp_line
			(start 0.12065 0.2794)
			(end 0.12065 0.3048)
			(stroke
				(width 0.1)
				(type default)
			)
			(layer "B.Fab")
		)
		(fp_line
			(start -0.120396 0.2794)
			(end 0.12065 0.2794)
			(stroke
				(width 0.1)
				(type default)
			)
			(layer "B.Fab")
		)
		(fp_line
			(start 0.67945 0.3048)
			(end 0.67945 -0.305054)
			(stroke
				(width 0.1)
				(type default)
			)
			(layer "B.Fab")
		)
		(fp_line
			(start 0.12065 0.3048)
			(end 0.67945 0.3048)
			(stroke
				(width 0.1)
				(type default)
			)
			(layer "B.Fab")
		)
		(fp_line
			(start -0.120396 0.3048)
			(end -0.120396 0.2794)
			(stroke
				(width 0.1)
				(type default)
			)
			(layer "B.Fab")
		)
		(fp_line
			(start -0.67945 0.3048)
			(end -0.120396 0.3048)
			(stroke
				(width 0.1)
				(type default)
			)
			(layer "B.Fab")
		)
		(pad "1" smd circle
			(at 0.40005 0 270)
			(size 0 0)
			(layers "B.Cu" "B.Mask" "B.Paste")
			(net "RST_SMB_SWITCH_R_N")
		)
		(pad "2" smd circle
			(at -0.40005 0 270)
			(size 0 0)
			(layers "B.Cu" "B.Mask" "B.Paste")
			(net "GND")
		)
	)
	(footprint ""
		(layer "B.Cu")
		(at 345.5543 -64.088264 90)
		(property "Reference" "C160"
			(at 0 0 90)
			(layer "B.SilkS")
			(hide yes)
			(effects
				(font
					(size 1.27 1.27)
				)
				(justify mirror)
			)
		)
		(property "Value" ""
			(at 0 0 90)
			(layer "B.Fab")
			(effects
				(font
					(size 1.27 1.27)
				)
				(justify mirror)
			)
		)
		(duplicate_pad_numbers_are_jumpers no)
		(fp_line
			(start 0.299974 -0.150114)
			(end -0.299974 -0.150114)
			(stroke
				(width 0.1)
				(type default)
			)
			(layer "B.Fab")
		)
		(fp_line
			(start -0.299974 -0.150114)
			(end -0.299974 0.150114)
			(stroke
				(width 0.1)
				(type default)
			)
			(layer "B.Fab")
		)
		(fp_line
			(start 0.299974 0.150114)
			(end 0.299974 -0.150114)
			(stroke
				(width 0.1)
				(type default)
			)
			(layer "B.Fab")
		)
		(fp_line
			(start -0.299974 0.150114)
			(end 0.299974 0.150114)
			(stroke
				(width 0.1)
				(type default)
			)
			(layer "B.Fab")
		)
		(pad "1" smd rect
			(at 0.2667 0 270)
			(size 0.3048 0.381)
			(layers "B.Cu" "B.Mask" "B.Paste")
			(net "DMI_CPU0_PCH_RX_C_DP<5>")
		)
		(pad "2" smd rect
			(at -0.2667 0 270)
			(size 0.3048 0.381)
			(layers "B.Cu" "B.Mask" "B.Paste")
			(net "DMI_CPU0_PCH_RX_DP<5>")
		)
	)
	(footprint ""
		(layer "B.Cu")
		(at 156.580078 -101.637846)
		(property "Reference" "R1329"
			(at 0 0 0)
			(layer "B.SilkS")
			(hide yes)
			(effects
				(font
					(size 1.27 1.27)
				)
				(justify mirror)
			)
		)
		(property "Value" ""
			(at 0 0 0)
			(layer "B.Fab")
			(effects
				(font
					(size 1.27 1.27)
				)
				(justify mirror)
			)
		)
		(duplicate_pad_numbers_are_jumpers no)
		(fp_line
			(start -0.7874 -0.4064)
			(end -0.7874 0.4064)
			(stroke
				(width 0.1524)
				(type default)
			)
			(layer "B.SilkS")
		)
		(fp_line
			(start -0.7874 0.4064)
			(end 0.7874 0.4064)
			(stroke
				(width 0.1524)
				(type default)
			)
			(layer "B.SilkS")
		)
		(fp_line
			(start 0.7874 -0.4064)
			(end -0.7874 -0.4064)
			(stroke
				(width 0.1524)
				(type default)
			)
			(layer "B.SilkS")
		)
		(fp_line
			(start 0.7874 0.4064)
			(end 0.7874 -0.4064)
			(stroke
				(width 0.1524)
				(type default)
			)
			(layer "B.SilkS")
		)
		(fp_line
			(start -0.67945 -0.3048)
			(end -0.67945 0.3048)
			(stroke
				(width 0.1)
				(type default)
			)
			(layer "B.Fab")
		)
		(fp_line
			(start -0.67945 0.3048)
			(end -0.120396 0.3048)
			(stroke
				(width 0.1)
				(type default)
			)
			(layer "B.Fab")
		)
		(fp_line
			(start -0.12065 -0.3048)
			(end -0.67945 -0.3048)
			(stroke
				(width 0.1)
				(type default)
			)
			(layer "B.Fab")
		)
		(fp_line
			(start -0.12065 -0.2794)
			(end -0.12065 -0.3048)
			(stroke
				(width 0.1)
				(type default)
			)
			(layer "B.Fab")
		)
		(fp_line
			(start -0.120396 0.2794)
			(end 0.12065 0.2794)
			(stroke
				(width 0.1)
				(type default)
			)
			(layer "B.Fab")
		)
		(fp_line
			(start -0.120396 0.3048)
			(end -0.120396 0.2794)
			(stroke
				(width 0.1)
				(type default)
			)
			(layer "B.Fab")
		)
		(fp_line
			(start 0.12065 -0.305054)
			(end 0.12065 -0.2794)
			(stroke
				(width 0.1)
				(type default)
			)
			(layer "B.Fab")
		)
		(fp_line
			(start 0.12065 -0.2794)
			(end -0.12065 -0.2794)
			(stroke
				(width 0.1)
				(type default)
			)
			(layer "B.Fab")
		)
		(fp_line
			(start 0.12065 0.2794)
			(end 0.12065 0.3048)
			(stroke
				(width 0.1)
				(type default)
			)
			(layer "B.Fab")
		)
		(fp_line
			(start 0.12065 0.3048)
			(end 0.67945 0.3048)
			(stroke
				(width 0.1)
				(type default)
			)
			(layer "B.Fab")
		)
		(fp_line
			(start 0.67945 -0.305054)
			(end 0.12065 -0.305054)
			(stroke
				(width 0.1)
				(type default)
			)
			(layer "B.Fab")
		)
		(fp_line
			(start 0.67945 0.3048)
			(end 0.67945 -0.305054)
			(stroke
				(width 0.1)
				(type default)
			)
			(layer "B.Fab")
		)
		(pad "1" smd circle
			(at 0.40005 0 180)
			(size 0 0)
			(layers "B.Cu" "B.Mask" "B.Paste")
			(net "PWRGD_DRAMPWRGD_CPU1_AB_R_LVC1")
		)
		(pad "2" smd circle
			(at -0.40005 0 180)
			(size 0 0)
			(layers "B.Cu" "B.Mask" "B.Paste")
			(net "GND")
		)
	)
)
